# T6G (Grand Teton) — schematic netlist excerpt (pin names and nets, part order shuffled) for the footprints in the layout excerpt that follows; sources: Cadence DE-HDL packaged netlist, KiCad conversion of 04192023_DAF0TMB3IC0_F0TG_MB_C_brd_V02_OCP.brd

PC6623  Q_CAP  100NF 50V 10% X7R  pkg C0402  page 365 : A = P0V9_CPU1_RT_2D ; B = GND
PC220  Q_CAPP  270UF 16V 20% OSCON  pkg THLF  page 208 : A = SW_P12V_AUX_PVDD11_S3_P0_FLT ; B = GND
R923  Q_RES  4.7K 5% CHIP  pkg 0201LF  page 353 : A = TEST2_RT_CPU1_P3 ; B = GND

(kicad_pcb
	(version 20260206)
	(generator "pcbnew")
	(generator_version "10.0")
	(general
		(thickness 1.6)
		(legacy_teardrops no)
	)
	(paper "A4")
	(title_block
		(title "04192023_DAF0TMB3IC0_F0TG_MB_C_brd_V02_OCP.brd")
		(comment 1 "Grand Teton / footprints 3427-3429 of 8354")
	)
	(layers
		(0 "F.Cu" signal "TOP")
		(4 "In1.Cu" signal "GND")
		(6 "In2.Cu" signal "IN1")
		(8 "In3.Cu" signal "GND1")
		(10 "In4.Cu" signal "IN2")
		(12 "In5.Cu" signal "GND2")
		(14 "In6.Cu" signal "IN3")
		(16 "In7.Cu" signal "GND3")
		(18 "In8.Cu" signal "VCC")
		(20 "In9.Cu" signal "VCC1")
		(22 "In10.Cu" signal "GND4")
		(24 "In11.Cu" signal "IN4")
		(26 "In12.Cu" signal "GND5")
		(28 "In13.Cu" signal "IN5")
		(30 "In14.Cu" signal "GND6")
		(32 "In15.Cu" signal "IN6")
		(34 "In16.Cu" signal "GND7")
		(2 "B.Cu" signal "BOTTOM")
		(9 "F.Adhes" user "F.Adhesive")
		(11 "B.Adhes" user "B.Adhesive")
		(13 "F.Paste" user "Package Geometry/Pastemask Top")
		(15 "B.Paste" user "Package Geometry/Pastemask Bottom")
		(5 "F.SilkS" user "Ref Des/Silkscreen Top")
		(7 "B.SilkS" user "Ref Des/Silkscreen Bottom")
		(1 "F.Mask" user "Board Geometry/Soldermask Top")
		(3 "B.Mask" user "Board Geometry/Soldermask Bottom")
		(17 "Dwgs.User" user "User.Drawings")
		(19 "Cmts.User" user "User.Comments")
		(21 "Eco1.User" user "User.Eco1")
		(23 "Eco2.User" user "User.Eco2")
		(25 "Edge.Cuts" user "Board Geometry/Outline")
		(27 "Margin" user)
		(31 "F.CrtYd" user "Package Geometry/Place Bound Top")
		(29 "B.CrtYd" user "Package Geometry/Place Bound Bottom")
		(35 "F.Fab" user "Ref Des/Assembly Top")
		(33 "B.Fab" user "Ref Des/Assembly Bottom")
	)
	(footprint ""
		(layer "F.Cu")
		(at 110.365794 -383.7432)
		(property "Reference" "R923"
			(at 0 0 0)
			(layer "F.SilkS")
			(hide yes)
			(effects
				(font
					(size 1.27 1.27)
				)
			)
		)
		(property "Value" ""
			(at 0 0 0)
			(layer "F.Fab")
			(effects
				(font
					(size 1.27 1.27)
				)
			)
		)
		(duplicate_pad_numbers_are_jumpers no)
		(fp_line
			(start -0.32512 -0.175006)
			(end 0.32512 -0.175006)
			(stroke
				(width 0.1)
				(type default)
			)
			(layer "F.Fab")
		)
		(fp_line
			(start -0.32512 0.175006)
			(end -0.32512 -0.175006)
			(stroke
				(width 0.1)
				(type default)
			)
			(layer "F.Fab")
		)
		(fp_line
			(start 0.32512 -0.175006)
			(end 0.32512 0.175006)
			(stroke
				(width 0.1)
				(type default)
			)
			(layer "F.Fab")
		)
		(fp_line
			(start 0.32512 0.175006)
			(end -0.32512 0.175006)
			(stroke
				(width 0.1)
				(type default)
			)
			(layer "F.Fab")
		)
		(pad "1" smd rect
			(at -0.2667 0)
			(size 0.3048 0.381)
			(layers "F.Cu" "F.Mask" "F.Paste")
			(net "TEST2_RT_CPU1_P3")
		)
		(pad "2" smd rect
			(at 0.2667 0 180)
			(size 0.3048 0.381)
			(layers "F.Cu" "F.Mask" "F.Paste")
			(net "GND")
		)
	)
	(footprint ""
		(layer "F.Cu")
		(at 13.21816 -381.202438 90)
		(property "Reference" "PC6623"
			(at 0 0 90)
			(layer "F.SilkS")
			(hide yes)
			(effects
				(font
					(size 1.27 1.27)
				)
			)
		)
		(property "Value" ""
			(at 0 0 90)
			(layer "F.Fab")
			(effects
				(font
					(size 1.27 1.27)
				)
			)
		)
		(duplicate_pad_numbers_are_jumpers no)
		(fp_line
			(start 0.7874 -0.4064)
			(end 0.7874 0.4064)
			(stroke
				(width 0.1524)
				(type default)
			)
			(layer "F.SilkS")
		)
		(fp_line
			(start -0.7874 -0.4064)
			(end 0.7874 -0.4064)
			(stroke
				(width 0.1524)
				(type default)
			)
			(layer "F.SilkS")
		)
		(fp_line
			(start 0.7874 0.4064)
			(end -0.7874 0.4064)
			(stroke
				(width 0.1524)
				(type default)
			)
			(layer "F.SilkS")
		)
		(fp_line
			(start -0.7874 0.4064)
			(end -0.7874 -0.4064)
			(stroke
				(width 0.1524)
				(type default)
			)
			(layer "F.SilkS")
		)
		(fp_line
			(start -0.12065 -0.305054)
			(end -0.12065 -0.2794)
			(stroke
				(width 0.1)
				(type default)
			)
			(layer "F.Fab")
		)
		(fp_line
			(start -0.67945 -0.305054)
			(end -0.12065 -0.305054)
			(stroke
				(width 0.1)
				(type default)
			)
			(layer "F.Fab")
		)
		(fp_line
			(start 0.67945 -0.3048)
			(end 0.67945 0.3048)
			(stroke
				(width 0.1)
				(type default)
			)
			(layer "F.Fab")
		)
		(fp_line
			(start 0.12065 -0.3048)
			(end 0.67945 -0.3048)
			(stroke
				(width 0.1)
				(type default)
			)
			(layer "F.Fab")
		)
		(fp_line
			(start 0.12065 -0.2794)
			(end 0.12065 -0.3048)
			(stroke
				(width 0.1)
				(type default)
			)
			(layer "F.Fab")
		)
		(fp_line
			(start -0.12065 -0.2794)
			(end 0.12065 -0.2794)
			(stroke
				(width 0.1)
				(type default)
			)
			(layer "F.Fab")
		)
		(fp_line
			(start 0.120396 0.2794)
			(end -0.12065 0.2794)
			(stroke
				(width 0.1)
				(type default)
			)
			(layer "F.Fab")
		)
		(fp_line
			(start -0.12065 0.2794)
			(end -0.12065 0.3048)
			(stroke
				(width 0.1)
				(type default)
			)
			(layer "F.Fab")
		)
		(fp_line
			(start 0.67945 0.3048)
			(end 0.120396 0.3048)
			(stroke
				(width 0.1)
				(type default)
			)
			(layer "F.Fab")
		)
		(fp_line
			(start 0.120396 0.3048)
			(end 0.120396 0.2794)
			(stroke
				(width 0.1)
				(type default)
			)
			(layer "F.Fab")
		)
		(fp_line
			(start -0.12065 0.3048)
			(end -0.67945 0.3048)
			(stroke
				(width 0.1)
				(type default)
			)
			(layer "F.Fab")
		)
		(fp_line
			(start -0.67945 0.3048)
			(end -0.67945 -0.305054)
			(stroke
				(width 0.1)
				(type default)
			)
			(layer "F.Fab")
		)
		(pad "1" smd circle
			(at -0.40005 0 90)
			(size 0 0)
			(layers "F.Cu" "F.Mask" "F.Paste")
			(net "P0V9_CPU1_RT_2D")
		)
		(pad "2" smd circle
			(at 0.40005 0 90)
			(size 0 0)
			(layers "F.Cu" "F.Mask" "F.Paste")
			(net "GND")
		)
	)
	(footprint ""
		(layer "F.Cu")
		(at 432.01336 -361.827826 180)
		(property "Reference" "PC220"
			(at 1.87452 -2.965704 0)
			(unlocked yes)
			(layer "F.SilkS")
			(effects
				(font
					(size 0.7874 0.5842)
					(thickness 0.1524)
				)
				(justify left)
			)
		)
		(property "Value" ""
			(at 0 0 180)
			(layer "F.Fab")
			(effects
				(font
					(size 1.27 1.27)
				)
			)
		)
		(duplicate_pad_numbers_are_jumpers no)
		(fp_line
			(start -3.400044 1.249934)
			(end 3.400044 1.249934)
			(stroke
				(width 0.1524)
				(type default)
			)
			(layer "F.SilkS")
		)
		(fp_circle
			(center 0 1.249934)
			(end -3.400044 1.249934)
			(stroke
				(width 0.1524)
				(type default)
			)
			(fill no)
			(layer "F.SilkS")
		)
		(fp_poly
			(pts
				(arc
					(start 3.400044 1.249934)
					(mid 0 4.649978)
					(end -3.400044 1.249934)
				)
			)
			(stroke
				(width 0)
				(type default)
			)
			(fill yes)
			(layer "F.SilkS")
		)
		(fp_circle
			(center 0 1.249934)
			(end -3.400044 1.249934)
			(stroke
				(width 0.1)
				(type default)
			)
			(fill no)
			(layer "F.Fab")
		)
		(pad "1" thru_hole rect
			(at 0 0 180)
			(size 1.524 1.524)
			(drill 1.016)
			(layers "*.Cu" "*.Mask")
			(remove_unused_layers no)
			(net "SW_P12V_AUX_PVDD11_S3_P0_FLT")
			(clearance 0)
			(padstack
				(mode front_inner_back)
				(layer "Inner"
					(shape circle)
					(size 1.524 1.524)
					(clearance 0)
				)
				(layer "B.Cu"
					(shape rect)
					(size 1.524 1.524)
					(clearance 0)
				)
			)
		)
		(pad "2" thru_hole circle
			(at 0 2.500122 180)
			(size 1.524 1.524)
			(drill 1.016)
			(layers "*.Cu" "*.Mask")
			(remove_unused_layers no)
			(net "GND")
			(clearance 0)
		)
	)
)
